(kicad_pcb
	(version 20260206)
	(generator "pcbnew")
	(generator_version "10.0")
	(general
		(thickness 1.6)
		(legacy_teardrops no)
	)
	(paper "A4")
	(title_block
		(title "timecard-production-celestica-r4006 — R4006-B0001-02_R01.brd")
		(comment 1 "Time Appliance Project (Time Card) / footprints 1095-1099 of 1113")
	)
	(layers
		(0 "F.Cu" signal "TOP")
		(4 "In1.Cu" signal "L02_GND1")
		(6 "In2.Cu" signal "L03_SIG1")
		(8 "In3.Cu" signal "L04_GND2")
		(10 "In4.Cu" signal "L05_VCC1")
		(12 "In5.Cu" signal "L06_VCC2")
		(14 "In6.Cu" signal "L07_GND3")
		(16 "In7.Cu" signal "L08_SIG2")
		(18 "In8.Cu" signal "L09_GND4")
		(2 "B.Cu" signal "BOTTOM")
		(9 "F.Adhes" user "F.Adhesive")
		(11 "B.Adhes" user "B.Adhesive")
		(13 "F.Paste" user "Package Geometry/Pastemask Top")
		(15 "B.Paste" user "Package Geometry/Pastemask Bottom")
		(5 "F.SilkS" user "Ref Des/Silkscreen Top")
		(7 "B.SilkS" user "Ref Des/Silkscreen Bottom")
		(1 "F.Mask" user "Board Geometry/Soldermask Top")
		(3 "B.Mask" user "Board Geometry/Soldermask Bottom")
		(17 "Dwgs.User" user "User.Drawings")
		(19 "Cmts.User" user "User.Comments")
		(21 "Eco1.User" user "User.Eco1")
		(23 "Eco2.User" user "User.Eco2")
		(25 "Edge.Cuts" user "Board Geometry/Outline")
		(27 "Margin" user)
		(31 "F.CrtYd" user "Package Geometry/Place Bound Top")
		(29 "B.CrtYd" user "Package Geometry/Place Bound Bottom")
		(35 "F.Fab" user "Ref Des/Assembly Top")
		(33 "B.Fab" user "Ref Des/Assembly Bottom")
	)
	(footprint ""
		(layer "B.Cu")
		(at 30.34538 -17.99844)
		(property "Reference" "R1"
			(at 0.13462 -1.13919 0)
			(unlocked yes)
			(layer "B.SilkS")
			(effects
				(font
					(size 0.7874 0.5842)
					(thickness 0.1524)
				)
				(justify mirror)
			)
		)
		(property "Value" "VAL*"
			(at -0.02032 2.13233 0)
			(unlocked yes)
			(layer "B.Fab")
			(hide yes)
			(effects
				(font
					(size 0.7874 0.5842)
					(thickness 0.1524)
				)
				(justify mirror)
			)
		)
		(property "Device Type" "RESISTOR-G155-13300-01,330OHM,A"
			(at -0.008382 1.210564 0)
			(unlocked yes)
			(layer "B.Fab")
			(hide yes)
			(effects
				(font
					(size 0.7874 0.5842)
					(thickness 0.1524)
				)
				(justify mirror)
			)
		)
		(property "User Part Number" "PARTNUM*"
			(at -0.02032 4.024884 0)
			(unlocked yes)
			(layer "Cmts.User")
			(hide yes)
			(effects
				(font
					(size 0.7874 0.5842)
					(thickness 0.1524)
				)
				(justify mirror)
			)
		)
		(property "Tolerance" "TOL*"
			(at -0.044704 3.05435 0)
			(unlocked yes)
			(layer "Cmts.User")
			(hide yes)
			(effects
				(font
					(size 0.7874 0.5842)
					(thickness 0.1524)
				)
				(justify mirror)
			)
		)
		(duplicate_pad_numbers_are_jumpers no)
		(fp_line
			(start -1.143 -0.5588)
			(end 1.143 -0.5588)
			(stroke
				(width 0.1)
				(type default)
			)
			(layer "B.SilkS")
		)
		(fp_line
			(start -1.143 0.5588)
			(end -1.143 -0.5588)
			(stroke
				(width 0.1)
				(type default)
			)
			(layer "B.SilkS")
		)
		(fp_line
			(start 1.143 -0.5588)
			(end 1.143 0.5588)
			(stroke
				(width 0.1)
				(type default)
			)
			(layer "B.SilkS")
		)
		(fp_line
			(start 1.143 0.5588)
			(end -1.143 0.5588)
			(stroke
				(width 0.1)
				(type default)
			)
			(layer "B.SilkS")
		)
		(fp_rect
			(start 1.143 0.5588)
			(end -1.143 -0.5588)
			(stroke
				(width 0)
				(type default)
			)
			(fill no)
			(layer "B.CrtYd")
		)
		(fp_line
			(start -0.508 -0.3048)
			(end 0.508 -0.3048)
			(stroke
				(width 0.1)
				(type default)
			)
			(layer "B.Fab")
		)
		(fp_line
			(start -0.508 0.3048)
			(end -0.508 -0.3048)
			(stroke
				(width 0.1)
				(type default)
			)
			(layer "B.Fab")
		)
		(fp_line
			(start 0.508 -0.3048)
			(end 0.508 0.3048)
			(stroke
				(width 0.1)
				(type default)
			)
			(layer "B.Fab")
		)
		(fp_line
			(start 0.508 0.3048)
			(end -0.508 0.3048)
			(stroke
				(width 0.1)
				(type default)
			)
			(layer "B.Fab")
		)
		(pad "1" smd rect
			(at 0.5334 0 180)
			(size 0.7112 0.6096)
			(layers "B.Cu" "B.Mask" "B.Paste")
			(net "FPGA_OUT_SN_EEPROM_WP")
		)
		(pad "2" smd rect
			(at -0.5334 0 180)
			(size 0.7112 0.6096)
			(layers "B.Cu" "B.Mask" "B.Paste")
			(net "SN_EEPROM_WP")
		)
		(zone
			(layer "B.Cu")
			(hatch none 0.5)
			(connect_pads
				(clearance 0)
			)
			(min_thickness 0.25)
			(keepout
				(tracks allowed)
				(vias not_allowed)
				(pads allowed)
				(copperpour not_allowed)
				(footprints allowed)
			)
			(placement
				(enabled no)
				(sheetname "")
			)
			(fill
				(thermal_gap 0.5)
				(thermal_bridge_width 0.5)
				(island_removal_mode 0)
			)
			(polygon
				(pts
					(xy 30.42158 -17.69364) (xy 30.42158 -18.30324) (xy 30.26918 -18.30324) (xy 30.26918 -17.69364)
				)
			)
		)
	)
	(footprint ""
		(layer "B.Cu")
		(at 144.145 -104.267 90)
		(property "Reference" "R180"
			(at -1.143 0.98425 270)
			(unlocked yes)
			(layer "B.SilkS")
			(effects
				(font
					(size 0.635 0.4064)
					(thickness 0.1524)
				)
				(justify mirror)
			)
		)
		(property "Value" "VAL*"
			(at -0.02032 2.13233 90)
			(unlocked yes)
			(layer "B.Fab")
			(hide yes)
			(effects
				(font
					(size 0.7874 0.5842)
					(thickness 0.1524)
				)
				(justify mirror)
			)
		)
		(property "Tolerance" "TOL*"
			(at -0.044704 3.05435 90)
			(unlocked yes)
			(layer "Cmts.User")
			(hide yes)
			(effects
				(font
					(size 0.7874 0.5842)
					(thickness 0.1524)
				)
				(justify mirror)
			)
		)
		(property "User Part Number" "PARTNUM*"
			(at -0.02032 4.024884 90)
			(unlocked yes)
			(layer "Cmts.User")
			(hide yes)
			(effects
				(font
					(size 0.7874 0.5842)
					(thickness 0.1524)
				)
				(justify mirror)
			)
		)
		(property "Device Type" "RESISTOR-G155-11001-01,1KOHM,1%"
			(at -0.008382 1.210564 90)
			(unlocked yes)
			(layer "B.Fab")
			(hide yes)
			(effects
				(font
					(size 0.7874 0.5842)
					(thickness 0.1524)
				)
				(justify mirror)
			)
		)
		(duplicate_pad_numbers_are_jumpers no)
		(fp_line
			(start 1.143 -0.5588)
			(end 1.143 0.5588)
			(stroke
				(width 0.1)
				(type default)
			)
			(layer "B.SilkS")
		)
		(fp_line
			(start -1.143 -0.5588)
			(end 1.143 -0.5588)
			(stroke
				(width 0.1)
				(type default)
			)
			(layer "B.SilkS")
		)
		(fp_line
			(start 1.143 0.5588)
			(end -1.143 0.5588)
			(stroke
				(width 0.1)
				(type default)
			)
			(layer "B.SilkS")
		)
		(fp_line
			(start -1.143 0.5588)
			(end -1.143 -0.5588)
			(stroke
				(width 0.1)
				(type default)
			)
			(layer "B.SilkS")
		)
		(fp_rect
			(start -1.143 -0.5588)
			(end 1.143 0.5588)
			(stroke
				(width 0)
				(type default)
			)
			(fill no)
			(layer "B.CrtYd")
		)
		(fp_line
			(start 0.508 -0.3048)
			(end 0.508 0.3048)
			(stroke
				(width 0.1)
				(type default)
			)
			(layer "B.Fab")
		)
		(fp_line
			(start -0.508 -0.3048)
			(end 0.508 -0.3048)
			(stroke
				(width 0.1)
				(type default)
			)
			(layer "B.Fab")
		)
		(fp_line
			(start 0.508 0.3048)
			(end -0.508 0.3048)
			(stroke
				(width 0.1)
				(type default)
			)
			(layer "B.Fab")
		)
		(fp_line
			(start -0.508 0.3048)
			(end -0.508 -0.3048)
			(stroke
				(width 0.1)
				(type default)
			)
			(layer "B.Fab")
		)
		(pad "1" smd rect
			(at 0.5334 0 270)
			(size 0.7112 0.6096)
			(layers "B.Cu" "B.Mask" "B.Paste")
			(net "UNNAMED_14_OPTICAL_I142_A")
		)
		(pad "2" smd rect
			(at -0.5334 0 270)
			(size 0.7112 0.6096)
			(layers "B.Cu" "B.Mask" "B.Paste")
			(net "XP5R0V")
		)
		(zone
			(layer "B.Cu")
			(hatch none 0.5)
			(connect_pads
				(clearance 0)
			)
			(min_thickness 0.25)
			(keepout
				(tracks allowed)
				(vias not_allowed)
				(pads allowed)
				(copperpour not_allowed)
				(footprints allowed)
			)
			(placement
				(enabled no)
				(sheetname "")
			)
			(fill
				(thermal_gap 0.5)
				(thermal_bridge_width 0.5)
				(island_removal_mode 0)
			)
			(polygon
				(pts
					(xy 143.8402 -104.1908) (xy 144.4498 -104.1908) (xy 144.4498 -104.3432) (xy 143.8402 -104.3432)
				)
			)
		)
	)
	(footprint ""
		(layer "B.Cu")
		(at 143.256 -55.118 -90)
		(property "Reference" "SP3"
			(at 1.81737 -0.254 0)
			(unlocked yes)
			(layer "B.SilkS")
			(effects
				(font
					(size 0.7874 0.5842)
					(thickness 0.1524)
				)
				(justify mirror)
			)
		)
		(property "Value" ""
			(at 0 0 90)
			(layer "B.Fab")
			(effects
				(font
					(size 1.27 1.27)
				)
				(justify mirror)
			)
		)
		(duplicate_pad_numbers_are_jumpers no)
		(fp_rect
			(start 0.1778 0.3048)
			(end -0.1778 -0.3048)
			(stroke
				(width 0)
				(type default)
			)
			(fill yes)
			(layer "B.Paste")
		)
		(fp_rect
			(start 0.2286 0.3556)
			(end -0.2286 -0.3556)
			(stroke
				(width 0)
				(type default)
			)
			(fill no)
			(layer "B.CrtYd")
		)
		(fp_line
			(start -0.1397 0.2413)
			(end 0.1397 0.2413)
			(stroke
				(width 0.1)
				(type default)
			)
			(layer "B.Fab")
		)
		(fp_line
			(start 0.1397 0.2413)
			(end 0.1397 -0.2413)
			(stroke
				(width 0.1)
				(type default)
			)
			(layer "B.Fab")
		)
		(fp_line
			(start -0.1397 -0.2413)
			(end -0.1397 0.2413)
			(stroke
				(width 0.1)
				(type default)
			)
			(layer "B.Fab")
		)
		(fp_line
			(start 0.1397 -0.2413)
			(end -0.1397 -0.2413)
			(stroke
				(width 0.1)
				(type default)
			)
			(layer "B.Fab")
		)
		(pad "1" smd rect
			(at 0.1143 0 90)
			(size 0.127 0.6096)
			(layers "B.Cu" "B.Mask" "B.Paste")
			(net "SG")
		)
		(pad "2" smd rect
			(at -0.1143 0 90)
			(size 0.127 0.6096)
			(layers "B.Cu" "B.Mask" "B.Paste")
			(net "XP1R0V_AGND")
		)
	)
	(footprint ""
		(layer "B.Cu")
		(at 14.6558 -17.1704 90)
		(property "Reference" "R379"
			(at 2.2606 -0.08255 270)
			(unlocked yes)
			(layer "B.SilkS")
			(effects
				(font
					(size 0.635 0.4064)
					(thickness 0.1524)
				)
				(justify mirror)
			)
		)
		(property "Value" "VAL*"
			(at -0.02032 2.13233 90)
			(unlocked yes)
			(layer "B.Fab")
			(hide yes)
			(effects
				(font
					(size 0.7874 0.5842)
					(thickness 0.1524)
				)
				(justify mirror)
			)
		)
		(property "Tolerance" "TOL*"
			(at -0.044704 3.05435 90)
			(unlocked yes)
			(layer "Cmts.User")
			(hide yes)
			(effects
				(font
					(size 0.7874 0.5842)
					(thickness 0.1524)
				)
				(justify mirror)
			)
		)
		(property "User Part Number" "PARTNUM*"
			(at -0.02032 4.024884 90)
			(unlocked yes)
			(layer "Cmts.User")
			(hide yes)
			(effects
				(font
					(size 0.7874 0.5842)
					(thickness 0.1524)
				)
				(justify mirror)
			)
		)
		(property "Device Type" "RESISTOR-G155-14701-01,4.7KOHMA"
			(at -0.008382 1.210564 90)
			(unlocked yes)
			(layer "B.Fab")
			(hide yes)
			(effects
				(font
					(size 0.7874 0.5842)
					(thickness 0.1524)
				)
				(justify mirror)
			)
		)
		(duplicate_pad_numbers_are_jumpers no)
		(fp_line
			(start 1.143 -0.5588)
			(end 1.143 0.5588)
			(stroke
				(width 0.1)
				(type default)
			)
			(layer "B.SilkS")
		)
		(fp_line
			(start -1.143 -0.5588)
			(end 1.143 -0.5588)
			(stroke
				(width 0.1)
				(type default)
			)
			(layer "B.SilkS")
		)
		(fp_line
			(start 1.143 0.5588)
			(end -1.143 0.5588)
			(stroke
				(width 0.1)
				(type default)
			)
			(layer "B.SilkS")
		)
		(fp_line
			(start -1.143 0.5588)
			(end -1.143 -0.5588)
			(stroke
				(width 0.1)
				(type default)
			)
			(layer "B.SilkS")
		)
		(fp_rect
			(start -1.143 0.5588)
			(end 1.143 -0.5588)
			(stroke
				(width 0)
				(type default)
			)
			(fill no)
			(layer "B.CrtYd")
		)
		(fp_line
			(start 0.508 -0.3048)
			(end 0.508 0.3048)
			(stroke
				(width 0.1)
				(type default)
			)
			(layer "B.Fab")
		)
		(fp_line
			(start -0.508 -0.3048)
			(end 0.508 -0.3048)
			(stroke
				(width 0.1)
				(type default)
			)
			(layer "B.Fab")
		)
		(fp_line
			(start 0.508 0.3048)
			(end -0.508 0.3048)
			(stroke
				(width 0.1)
				(type default)
			)
			(layer "B.Fab")
		)
		(fp_line
			(start -0.508 0.3048)
			(end -0.508 -0.3048)
			(stroke
				(width 0.1)
				(type default)
			)
			(layer "B.Fab")
		)
		(pad "1" smd rect
			(at 0.5334 0 270)
			(size 0.7112 0.6096)
			(layers "B.Cu" "B.Mask" "B.Paste")
			(net "XP3R3V_FPGA")
		)
		(pad "2" smd rect
			(at -0.5334 0 270)
			(size 0.7112 0.6096)
			(layers "B.Cu" "B.Mask" "B.Paste")
			(net "SMA4_SIG_IN_BF_EN_N")
		)
		(zone
			(layer "B.Cu")
			(hatch none 0.5)
			(connect_pads
				(clearance 0)
			)
			(min_thickness 0.25)
			(keepout
				(tracks allowed)
				(vias not_allowed)
				(pads allowed)
				(copperpour not_allowed)
				(footprints allowed)
			)
			(placement
				(enabled no)
				(sheetname "")
			)
			(fill
				(thermal_gap 0.5)
				(thermal_bridge_width 0.5)
				(island_removal_mode 0)
			)
			(polygon
				(pts
					(xy 14.9606 -17.0942) (xy 14.9606 -17.2466) (xy 14.351 -17.2466) (xy 14.351 -17.0942)
				)
			)
		)
		(zone
			(layer "B.Cu")
			(hatch none 0.5)
			(connect_pads
				(clearance 0)
			)
			(min_thickness 0.25)
			(keepout
				(tracks not_allowed)
				(vias allowed)
				(pads allowed)
				(copperpour not_allowed)
				(footprints allowed)
			)
			(placement
				(enabled no)
				(sheetname "")
			)
			(fill
				(thermal_gap 0.5)
				(thermal_bridge_width 0.5)
				(island_removal_mode 0)
			)
			(polygon
				(pts
					(xy 14.9606 -17.0942) (xy 14.9606 -17.2466) (xy 14.351 -17.2466) (xy 14.351 -17.0942)
				)
			)
		)
	)
	(footprint ""
		(layer "B.Cu")
		(at 98.044 -95.4532)
		(property "Reference" "R451"
			(at 2.667 0.11557 0)
			(unlocked yes)
			(layer "B.SilkS")
			(effects
				(font
					(size 0.7874 0.5842)
					(thickness 0.1524)
				)
				(justify mirror)
			)
		)
		(property "Value" "VAL*"
			(at -0.02032 2.13233 0)
			(unlocked yes)
			(layer "B.Fab")
			(hide yes)
			(effects
				(font
					(size 0.7874 0.5842)
					(thickness 0.1524)
				)
				(justify mirror)
			)
		)
		(property "Tolerance" "TOL*"
			(at -0.044704 3.05435 0)
			(unlocked yes)
			(layer "Cmts.User")
			(hide yes)
			(effects
				(font
					(size 0.7874 0.5842)
					(thickness 0.1524)
				)
				(justify mirror)
			)
		)
		(property "User Part Number" "PARTNUM*"
			(at -0.02032 4.024884 0)
			(unlocked yes)
			(layer "Cmts.User")
			(hide yes)
			(effects
				(font
					(size 0.7874 0.5842)
					(thickness 0.1524)
				)
				(justify mirror)
			)
		)
		(property "Device Type" "RESISTOR-G155-11001-01,1KOHM,1%"
			(at -0.008382 1.210564 0)
			(unlocked yes)
			(layer "B.Fab")
			(hide yes)
			(effects
				(font
					(size 0.7874 0.5842)
					(thickness 0.1524)
				)
				(justify mirror)
			)
		)
		(duplicate_pad_numbers_are_jumpers no)
		(fp_line
			(start -1.143 -0.5588)
			(end 1.143 -0.5588)
			(stroke
				(width 0.1)
				(type default)
			)
			(layer "B.SilkS")
		)
		(fp_line
			(start -1.143 0.5588)
			(end -1.143 -0.5588)
			(stroke
				(width 0.1)
				(type default)
			)
			(layer "B.SilkS")
		)
		(fp_line
			(start 1.143 -0.5588)
			(end 1.143 0.5588)
			(stroke
				(width 0.1)
				(type default)
			)
			(layer "B.SilkS")
		)
		(fp_line
			(start 1.143 0.5588)
			(end -1.143 0.5588)
			(stroke
				(width 0.1)
				(type default)
			)
			(layer "B.SilkS")
		)
		(fp_poly
			(pts
				(xy 1.143 0.5588) (xy -1.143 0.5588) (xy -1.143 -0.5588) (xy 1.143 -0.5588)
			)
			(stroke
				(width 0)
				(type default)
			)
			(fill no)
			(layer "B.CrtYd")
		)
		(fp_line
			(start -0.508 -0.3048)
			(end 0.508 -0.3048)
			(stroke
				(width 0.1)
				(type default)
			)
			(layer "B.Fab")
		)
		(fp_line
			(start -0.508 0.3048)
			(end -0.508 -0.3048)
			(stroke
				(width 0.1)
				(type default)
			)
			(layer "B.Fab")
		)
		(fp_line
			(start 0.508 -0.3048)
			(end 0.508 0.3048)
			(stroke
				(width 0.1)
				(type default)
			)
			(layer "B.Fab")
		)
		(fp_line
			(start 0.508 0.3048)
			(end -0.508 0.3048)
			(stroke
				(width 0.1)
				(type default)
			)
			(layer "B.Fab")
		)
		(pad "1" smd rect
			(at 0.5334 0 180)
			(size 0.7112 0.6096)
			(layers "B.Cu" "B.Mask" "B.Paste")
			(net "MUX1_SEL")
		)
		(pad "2" smd rect
			(at -0.5334 0 180)
			(size 0.7112 0.6096)
			(layers "B.Cu" "B.Mask" "B.Paste")
			(net "SG")
		)
		(zone
			(layer "B.Cu")
			(hatch none 0.5)
			(connect_pads
				(clearance 0)
			)
			(min_thickness 0.25)
			(keepout
				(tracks not_allowed)
				(vias allowed)
				(pads allowed)
				(copperpour not_allowed)
				(footprints allowed)
			)
			(placement
				(enabled no)
				(sheetname "")
			)
			(fill
				(thermal_gap 0.5)
				(thermal_bridge_width 0.5)
				(island_removal_mode 0)
			)
			(polygon
				(pts
					(xy 98.1202 -95.1484) (xy 98.1202 -95.758) (xy 97.9678 -95.758) (xy 97.9678 -95.1484)
				)
			)
		)
		(zone
			(layer "B.Cu")
			(hatch none 0.5)
			(connect_pads
				(clearance 0)
			)
			(min_thickness 0.25)
			(keepout
				(tracks allowed)
				(vias not_allowed)
				(pads allowed)
				(copperpour not_allowed)
				(footprints allowed)
			)
			(placement
				(enabled no)
				(sheetname "")
			)
			(fill
				(thermal_gap 0.5)
				(thermal_bridge_width 0.5)
				(island_removal_mode 0)
			)
			(polygon
				(pts
					(xy 98.1202 -95.1484) (xy 98.1202 -95.758) (xy 97.9678 -95.758) (xy 97.9678 -95.1484)
				)
			)
		)
	)
)
